(kicad_pcb
	(version 20260206)
	(generator "pcbnew")
	(generator_version "10.0")
	(general
		(thickness 1.6)
		(legacy_teardrops no)
	)
	(paper "A4")
	(title_block
		(title "panther-plus-userver — 13130-1b_20150205.brd")
		(comment 1 "Honey Badger (Wiwynn) / footprints 895-902 of 1509")
	)
	(layers
		(0 "F.Cu" signal "TOP")
		(4 "In1.Cu" signal "L2")
		(6 "In2.Cu" signal "L3")
		(8 "In3.Cu" signal "L4")
		(10 "In4.Cu" signal "L5")
		(12 "In5.Cu" signal "L6")
		(14 "In6.Cu" signal "L7")
		(16 "In7.Cu" signal "L8")
		(18 "In8.Cu" signal "L9")
		(20 "In9.Cu" signal "L10")
		(22 "In10.Cu" signal "L11")
		(2 "B.Cu" signal "BOTTOM")
		(9 "F.Adhes" user "F.Adhesive")
		(11 "B.Adhes" user "B.Adhesive")
		(13 "F.Paste" user "Package Geometry/Pastemask Top")
		(15 "B.Paste" user "Package Geometry/Pastemask Bottom")
		(5 "F.SilkS" user "Ref Des/Silkscreen Top")
		(7 "B.SilkS" user "Ref Des/Silkscreen Bottom")
		(1 "F.Mask" user "Board Geometry/Soldermask Top")
		(3 "B.Mask" user "Board Geometry/Soldermask Bottom")
		(17 "Dwgs.User" user "User.Drawings")
		(19 "Cmts.User" user "User.Comments")
		(21 "Eco1.User" user "User.Eco1")
		(23 "Eco2.User" user "User.Eco2")
		(25 "Edge.Cuts" user "Board Geometry/Outline")
		(27 "Margin" user)
		(31 "F.CrtYd" user "Package Geometry/Place Bound Top")
		(29 "B.CrtYd" user "Package Geometry/Place Bound Bottom")
		(35 "F.Fab" user "Ref Des/Assembly Top")
		(33 "B.Fab" user "Ref Des/Assembly Bottom")
	)
	(footprint ""
		(layer "B.Cu")
		(at 68.072 -13.589)
		(property "Reference" "C281"
			(at 0 0 0)
			(layer "B.SilkS")
			(hide yes)
			(effects
				(font
					(size 1.27 1.27)
				)
				(justify mirror)
			)
		)
		(property "Value" "SCD1U16V2KX-3GP"
			(at -1.1811 -2.7051 0)
			(unlocked yes)
			(layer "B.Fab")
			(hide yes)
			(effects
				(font
					(size 1.016 1.016)
					(thickness 0.1524)
				)
				(justify mirror)
			)
		)
		(property "Device Type" "C402H22"
			(at -1.1811 -4.2291 0)
			(unlocked yes)
			(layer "B.Fab")
			(hide yes)
			(effects
				(font
					(size 1.016 1.016)
					(thickness 0.1524)
				)
				(justify mirror)
			)
		)
		(duplicate_pad_numbers_are_jumpers no)
		(fp_rect
			(start 0.381 0.7366)
			(end -0.381 -0.7366)
			(stroke
				(width 0)
				(type default)
			)
			(fill no)
			(layer "B.CrtYd")
		)
		(fp_rect
			(start 0.381 0.7366)
			(end -0.381 -0.7366)
			(stroke
				(width 0)
				(type default)
			)
			(fill no)
			(layer "B.Fab")
		)
		(pad "1" smd custom
			(at 0 -0.4572 180)
			(size 0.1143 0.1143)
			(layers "B.Cu" "B.Mask" "B.Paste")
			(net "P2E_CPU_SAS_C_TX_DN3")
			(options
				(clearance outline)
				(anchor circle)
			)
			(primitives
				(gr_poly
					(pts
						(arc
							(start -0.254 0.1778)
							(mid -0.239121 0.213721)
							(end -0.2032 0.2286)
						)
						(arc
							(start 0.2032 0.2286)
							(mid 0.239121 0.213721)
							(end 0.254 0.1778)
						)
						(arc
							(start 0.254 -0.1778)
							(mid 0.239121 -0.213721)
							(end 0.2032 -0.2286)
						)
						(arc
							(start -0.2032 -0.2286)
							(mid -0.239121 -0.213721)
							(end -0.254 -0.1778)
						)
					)
					(width 0)
					(fill yes)
				)
			)
		)
		(pad "2" smd custom
			(at 0 0.4572 180)
			(size 0.1143 0.1143)
			(layers "B.Cu" "B.Mask" "B.Paste")
			(net "P2E_CPU_SAS_TX_DN3")
			(options
				(clearance outline)
				(anchor circle)
			)
			(primitives
				(gr_poly
					(pts
						(arc
							(start -0.254 0.1778)
							(mid -0.239121 0.213721)
							(end -0.2032 0.2286)
						)
						(arc
							(start 0.2032 0.2286)
							(mid 0.239121 0.213721)
							(end 0.254 0.1778)
						)
						(arc
							(start 0.254 -0.1778)
							(mid 0.239121 -0.213721)
							(end 0.2032 -0.2286)
						)
						(arc
							(start -0.2032 -0.2286)
							(mid -0.239121 -0.213721)
							(end -0.254 -0.1778)
						)
					)
					(width 0)
					(fill yes)
				)
			)
		)
	)
	(footprint ""
		(layer "B.Cu")
		(at 70.7644 -37.4904 180)
		(property "Reference" "PR129"
			(at 0 0 0)
			(layer "B.SilkS")
			(hide yes)
			(effects
				(font
					(size 1.27 1.27)
				)
				(justify mirror)
			)
		)
		(property "Value" "0R2J-2-GP"
			(at -0.064008 -3.993896 180)
			(unlocked yes)
			(layer "B.Fab")
			(hide yes)
			(effects
				(font
					(size 1.016 1.016)
					(thickness 0.1524)
				)
				(justify mirror)
			)
		)
		(property "Device Type" "R402H16"
			(at -0.064008 -5.517896 180)
			(unlocked yes)
			(layer "B.Fab")
			(hide yes)
			(effects
				(font
					(size 1.016 1.016)
					(thickness 0.1524)
				)
				(justify mirror)
			)
		)
		(duplicate_pad_numbers_are_jumpers no)
		(fp_rect
			(start 0.381 0.8382)
			(end -0.381 -0.8382)
			(stroke
				(width 0)
				(type default)
			)
			(fill no)
			(layer "B.CrtYd")
		)
		(fp_rect
			(start 0.381 0.8382)
			(end -0.381 -0.8382)
			(stroke
				(width 0)
				(type default)
			)
			(fill no)
			(layer "B.Fab")
		)
		(pad "1" smd custom
			(at 0 -0.4318)
			(size 0.127 0.127)
			(layers "B.Cu" "B.Mask" "B.Paste")
			(net "PMU_SLP_S3#")
			(options
				(clearance outline)
				(anchor circle)
			)
			(primitives
				(gr_poly
					(pts
						(arc
							(start -0.2032 0.2794)
							(mid -0.239121 0.264521)
							(end -0.254 0.2286)
						)
						(arc
							(start -0.254 -0.2286)
							(mid -0.239121 -0.264521)
							(end -0.2032 -0.2794)
						)
						(arc
							(start 0.2032 -0.2794)
							(mid 0.239121 -0.264521)
							(end 0.254 -0.2286)
						)
						(arc
							(start 0.254 0.2286)
							(mid 0.239121 0.264521)
							(end 0.2032 0.2794)
						)
					)
					(width 0)
					(fill yes)
				)
			)
		)
		(pad "2" smd custom
			(at 0 0.4318)
			(size 0.127 0.127)
			(layers "B.Cu" "B.Mask" "B.Paste")
			(net "PMU_SLP_INB_S3#")
			(options
				(clearance outline)
				(anchor circle)
			)
			(primitives
				(gr_poly
					(pts
						(arc
							(start -0.2032 0.2794)
							(mid -0.239121 0.264521)
							(end -0.254 0.2286)
						)
						(arc
							(start -0.254 -0.2286)
							(mid -0.239121 -0.264521)
							(end -0.2032 -0.2794)
						)
						(arc
							(start 0.2032 -0.2794)
							(mid 0.239121 -0.264521)
							(end 0.254 -0.2286)
						)
						(arc
							(start 0.254 0.2286)
							(mid 0.239121 0.264521)
							(end 0.2032 0.2794)
						)
					)
					(width 0)
					(fill yes)
				)
			)
		)
	)
	(footprint ""
		(layer "B.Cu")
		(at 109.22 -21.59 90)
		(property "Reference" "C260"
			(at 0 0 90)
			(layer "B.SilkS")
			(hide yes)
			(effects
				(font
					(size 1.27 1.27)
				)
				(justify mirror)
			)
		)
		(property "Value" "SC22U6D3V5MX-2GP"
			(at 0.0762 -6.1214 90)
			(unlocked yes)
			(layer "B.Fab")
			(hide yes)
			(effects
				(font
					(size 1.016 1.016)
					(thickness 0.1524)
				)
				(justify mirror)
			)
		)
		(property "Device Type" "C805H58"
			(at 0.0762 -8.1534 90)
			(unlocked yes)
			(layer "B.Fab")
			(hide yes)
			(effects
				(font
					(size 1.016 1.016)
					(thickness 0.1524)
				)
				(justify mirror)
			)
		)
		(duplicate_pad_numbers_are_jumpers no)
		(fp_line
			(start -0.6096 0)
			(end 0.6096 0)
			(stroke
				(width 0.3048)
				(type default)
			)
			(layer "B.SilkS")
		)
		(fp_poly
			(pts
				(xy 0.9017 1.4351) (xy -0.9017 1.4351) (xy -0.9017 -1.4351) (xy 0.9017 -1.4351)
			)
			(stroke
				(width 0)
				(type default)
			)
			(fill no)
			(layer "B.CrtYd")
		)
		(fp_poly
			(pts
				(xy -0.9017 1.4351) (xy -0.9017 -1.4351) (xy 0.9017 -1.4351) (xy 0.9017 1.4351)
			)
			(stroke
				(width 0)
				(type default)
			)
			(fill no)
			(layer "B.Fab")
		)
		(pad "1" smd rect
			(at 0 -0.8382 270)
			(size 1.5494 0.9398)
			(layers "B.Cu" "B.Mask" "B.Paste")
			(net "PV_VDDR")
		)
		(pad "2" smd rect
			(at 0 0.8382 270)
			(size 1.5494 0.9398)
			(layers "B.Cu" "B.Mask" "B.Paste")
			(net "GND")
		)
	)
	(footprint ""
		(layer "B.Cu")
		(at 88.519 -24.003 -90)
		(property "Reference" "C261"
			(at 0 0 90)
			(layer "B.SilkS")
			(hide yes)
			(effects
				(font
					(size 1.27 1.27)
				)
				(justify mirror)
			)
		)
		(property "Value" "SC1U10V2KX-1GP"
			(at -1.1811 -2.7051 270)
			(unlocked yes)
			(layer "B.Fab")
			(hide yes)
			(effects
				(font
					(size 1.016 1.016)
					(thickness 0.1524)
				)
				(justify mirror)
			)
		)
		(property "Device Type" "C402H22"
			(at -1.1811 -4.2291 270)
			(unlocked yes)
			(layer "B.Fab")
			(hide yes)
			(effects
				(font
					(size 1.016 1.016)
					(thickness 0.1524)
				)
				(justify mirror)
			)
		)
		(duplicate_pad_numbers_are_jumpers no)
		(fp_rect
			(start 0.381 0.7366)
			(end -0.381 -0.7366)
			(stroke
				(width 0)
				(type default)
			)
			(fill no)
			(layer "B.CrtYd")
		)
		(fp_rect
			(start 0.381 0.7366)
			(end -0.381 -0.7366)
			(stroke
				(width 0)
				(type default)
			)
			(fill no)
			(layer "B.Fab")
		)
		(pad "1" smd custom
			(at 0 -0.4572 90)
			(size 0.1143 0.1143)
			(layers "B.Cu" "B.Mask" "B.Paste")
			(net "P1V0")
			(options
				(clearance outline)
				(anchor circle)
			)
			(primitives
				(gr_poly
					(pts
						(arc
							(start -0.254 0.1778)
							(mid -0.239121 0.213721)
							(end -0.2032 0.2286)
						)
						(arc
							(start 0.2032 0.2286)
							(mid 0.239121 0.213721)
							(end 0.254 0.1778)
						)
						(arc
							(start 0.254 -0.1778)
							(mid 0.239121 -0.213721)
							(end 0.2032 -0.2286)
						)
						(arc
							(start -0.2032 -0.2286)
							(mid -0.239121 -0.213721)
							(end -0.254 -0.1778)
						)
					)
					(width 0)
					(fill yes)
				)
			)
		)
		(pad "2" smd custom
			(at 0 0.4572 90)
			(size 0.1143 0.1143)
			(layers "B.Cu" "B.Mask" "B.Paste")
			(net "GND")
			(options
				(clearance outline)
				(anchor circle)
			)
			(primitives
				(gr_poly
					(pts
						(arc
							(start -0.254 0.1778)
							(mid -0.239121 0.213721)
							(end -0.2032 0.2286)
						)
						(arc
							(start 0.2032 0.2286)
							(mid 0.239121 0.213721)
							(end 0.254 0.1778)
						)
						(arc
							(start 0.254 -0.1778)
							(mid 0.239121 -0.213721)
							(end 0.2032 -0.2286)
						)
						(arc
							(start -0.2032 -0.2286)
							(mid -0.239121 -0.213721)
							(end -0.254 -0.1778)
						)
					)
					(width 0)
					(fill yes)
				)
			)
		)
	)
	(footprint ""
		(layer "B.Cu")
		(at 24.765 -49.022 90)
		(property "Reference" "PR179"
			(at 0 0 90)
			(layer "B.SilkS")
			(hide yes)
			(effects
				(font
					(size 1.27 1.27)
				)
				(justify mirror)
			)
		)
		(property "Value" "0R3J-6-GP"
			(at 0.0254 -2.0193 90)
			(unlocked yes)
			(layer "B.Fab")
			(hide yes)
			(effects
				(font
					(size 1.016 1.016)
					(thickness 0.1524)
				)
				(justify mirror)
			)
		)
		(property "Device Type" "R603H22"
			(at 0.0254 -3.5433 90)
			(unlocked yes)
			(layer "B.Fab")
			(hide yes)
			(effects
				(font
					(size 1.016 1.016)
					(thickness 0.1524)
				)
				(justify mirror)
			)
		)
		(duplicate_pad_numbers_are_jumpers no)
		(fp_line
			(start 0.2032 0)
			(end 0.4191 0)
			(stroke
				(width 0.2032)
				(type default)
			)
			(layer "B.SilkS")
		)
		(fp_line
			(start -0.4318 0)
			(end -0.2032 0)
			(stroke
				(width 0.2032)
				(type default)
			)
			(layer "B.SilkS")
		)
		(fp_rect
			(start 0.635 1.1811)
			(end -0.635 -1.1811)
			(stroke
				(width 0)
				(type default)
			)
			(fill no)
			(layer "B.CrtYd")
		)
		(fp_rect
			(start 0.635 1.1811)
			(end -0.635 -1.1811)
			(stroke
				(width 0)
				(type default)
			)
			(fill no)
			(layer "B.Fab")
		)
		(pad "1" smd custom
			(at 0 -0.6604 270)
			(size 0.19685 0.19685)
			(layers "B.Cu" "B.Mask" "B.Paste")
			(net "P1V8_STBY")
			(options
				(clearance outline)
				(anchor circle)
			)
			(primitives
				(gr_poly
					(pts
						(arc
							(start 0.508 0.2921)
							(mid 0.478242 0.363942)
							(end 0.4064 0.3937)
						)
						(arc
							(start -0.4064 0.3937)
							(mid -0.478242 0.363942)
							(end -0.508 0.2921)
						)
						(arc
							(start -0.508 -0.2921)
							(mid -0.478242 -0.363942)
							(end -0.4064 -0.3937)
						)
						(arc
							(start 0.4064 -0.3937)
							(mid 0.478242 -0.363942)
							(end 0.508 -0.2921)
						)
					)
					(width 0)
					(fill yes)
				)
			)
		)
		(pad "2" smd custom
			(at 0 0.6604 270)
			(size 0.19685 0.19685)
			(layers "B.Cu" "B.Mask" "B.Paste")
			(net "P1V5_STBY_IN")
			(options
				(clearance outline)
				(anchor circle)
			)
			(primitives
				(gr_poly
					(pts
						(arc
							(start 0.508 0.2921)
							(mid 0.478242 0.363942)
							(end 0.4064 0.3937)
						)
						(arc
							(start -0.4064 0.3937)
							(mid -0.478242 0.363942)
							(end -0.508 0.2921)
						)
						(arc
							(start -0.508 -0.2921)
							(mid -0.478242 -0.363942)
							(end -0.4064 -0.3937)
						)
						(arc
							(start 0.4064 -0.3937)
							(mid 0.478242 -0.363942)
							(end 0.508 -0.2921)
						)
					)
					(width 0)
					(fill yes)
				)
			)
		)
	)
	(footprint ""
		(layer "B.Cu")
		(at 94.234 -44.6151 90)
		(property "Reference" "L6"
			(at 0 0 90)
			(layer "B.SilkS")
			(hide yes)
			(effects
				(font
					(size 1.27 1.27)
				)
				(justify mirror)
			)
		)
		(property "Value" "BLM18PG121SN1D-GP"
			(at 0.0254 -2.8956 90)
			(unlocked yes)
			(layer "B.Fab")
			(hide yes)
			(effects
				(font
					(size 1.016 1.016)
					(thickness 0.1524)
				)
				(justify mirror)
			)
		)
		(property "Device Type" "L1608-UH38"
			(at 0.0254 -4.4196 90)
			(unlocked yes)
			(layer "B.Fab")
			(hide yes)
			(effects
				(font
					(size 1.016 1.016)
					(thickness 0.1524)
				)
				(justify mirror)
			)
		)
		(duplicate_pad_numbers_are_jumpers no)
		(fp_line
			(start 0.4064 0)
			(end -0.4064 0)
			(stroke
				(width 0.2032)
				(type default)
			)
			(layer "B.SilkS")
		)
		(fp_rect
			(start 0.635 1.1811)
			(end -0.635 -1.1811)
			(stroke
				(width 0)
				(type default)
			)
			(fill no)
			(layer "B.CrtYd")
		)
		(fp_rect
			(start 0.635 1.1811)
			(end -0.635 -1.1811)
			(stroke
				(width 0)
				(type default)
			)
			(fill no)
			(layer "B.Fab")
		)
		(pad "1" smd custom
			(at 0 -0.6604 270)
			(size 0.19685 0.19685)
			(layers "B.Cu" "B.Mask" "B.Paste")
			(net "P1V0")
			(options
				(clearance outline)
				(anchor circle)
			)
			(primitives
				(gr_poly
					(pts
						(arc
							(start 0.508 0.2921)
							(mid 0.478242 0.363942)
							(end 0.4064 0.3937)
						)
						(arc
							(start -0.4064 0.3937)
							(mid -0.478242 0.363942)
							(end -0.508 0.2921)
						)
						(arc
							(start -0.508 -0.2921)
							(mid -0.478242 -0.363942)
							(end -0.4064 -0.3937)
						)
						(arc
							(start 0.4064 -0.3937)
							(mid 0.478242 -0.363942)
							(end 0.508 -0.2921)
						)
					)
					(width 0)
					(fill yes)
				)
			)
		)
		(pad "2" smd custom
			(at 0 0.6604 270)
			(size 0.19685 0.19685)
			(layers "B.Cu" "B.Mask" "B.Paste")
			(net "VCCA_PLLDDR0_AVN")
			(options
				(clearance outline)
				(anchor circle)
			)
			(primitives
				(gr_poly
					(pts
						(arc
							(start 0.508 0.2921)
							(mid 0.478242 0.363942)
							(end 0.4064 0.3937)
						)
						(arc
							(start -0.4064 0.3937)
							(mid -0.478242 0.363942)
							(end -0.508 0.2921)
						)
						(arc
							(start -0.508 -0.2921)
							(mid -0.478242 -0.363942)
							(end -0.4064 -0.3937)
						)
						(arc
							(start 0.4064 -0.3937)
							(mid 0.478242 -0.363942)
							(end 0.508 -0.2921)
						)
					)
					(width 0)
					(fill yes)
				)
			)
		)
	)
	(footprint ""
		(layer "B.Cu")
		(at 15.875 -63.881 90)
		(property "Reference" "C31"
			(at 0 0 90)
			(layer "B.SilkS")
			(hide yes)
			(effects
				(font
					(size 1.27 1.27)
				)
				(justify mirror)
			)
		)
		(property "Value" "SC1U6D3V2KX-GP"
			(at -1.8923 -1.2065 90)
			(unlocked yes)
			(layer "B.Fab")
			(hide yes)
			(effects
				(font
					(size 1.016 1.016)
					(thickness 0.1524)
				)
				(justify mirror)
			)
		)
		(property "Device Type" "C402H22"
			(at -1.8923 -2.7305 90)
			(unlocked yes)
			(layer "B.Fab")
			(hide yes)
			(effects
				(font
					(size 1.016 1.016)
					(thickness 0.1524)
				)
				(justify mirror)
			)
		)
		(duplicate_pad_numbers_are_jumpers no)
		(fp_rect
			(start 0.381 0.7366)
			(end -0.381 -0.7366)
			(stroke
				(width 0)
				(type default)
			)
			(fill no)
			(layer "B.CrtYd")
		)
		(fp_rect
			(start 0.381 0.7366)
			(end -0.381 -0.7366)
			(stroke
				(width 0)
				(type default)
			)
			(fill no)
			(layer "B.Fab")
		)
		(pad "1" smd custom
			(at 0 -0.4572 270)
			(size 0.1143 0.1143)
			(layers "B.Cu" "B.Mask" "B.Paste")
			(net "P3V3")
			(options
				(clearance outline)
				(anchor circle)
			)
			(primitives
				(gr_poly
					(pts
						(arc
							(start -0.254 0.1778)
							(mid -0.239121 0.213721)
							(end -0.2032 0.2286)
						)
						(arc
							(start 0.2032 0.2286)
							(mid 0.239121 0.213721)
							(end 0.254 0.1778)
						)
						(arc
							(start 0.254 -0.1778)
							(mid 0.239121 -0.213721)
							(end 0.2032 -0.2286)
						)
						(arc
							(start -0.2032 -0.2286)
							(mid -0.239121 -0.213721)
							(end -0.254 -0.1778)
						)
					)
					(width 0)
					(fill yes)
				)
			)
		)
		(pad "2" smd custom
			(at 0 0.4572 270)
			(size 0.1143 0.1143)
			(layers "B.Cu" "B.Mask" "B.Paste")
			(net "GND")
			(options
				(clearance outline)
				(anchor circle)
			)
			(primitives
				(gr_poly
					(pts
						(arc
							(start -0.254 0.1778)
							(mid -0.239121 0.213721)
							(end -0.2032 0.2286)
						)
						(arc
							(start 0.2032 0.2286)
							(mid 0.239121 0.213721)
							(end 0.254 0.1778)
						)
						(arc
							(start 0.254 -0.1778)
							(mid 0.239121 -0.213721)
							(end 0.2032 -0.2286)
						)
						(arc
							(start -0.2032 -0.2286)
							(mid -0.239121 -0.213721)
							(end -0.254 -0.1778)
						)
					)
					(width 0)
					(fill yes)
				)
			)
		)
	)
	(footprint ""
		(layer "B.Cu")
		(at 197.739 -2.9718 90)
		(property "Reference" "C288"
			(at 0 0 90)
			(layer "B.SilkS")
			(hide yes)
			(effects
				(font
					(size 1.27 1.27)
				)
				(justify mirror)
			)
		)
		(property "Value" "SC10U6D3V3MX-GP"
			(at 0 -2.8194 90)
			(unlocked yes)
			(layer "B.Fab")
			(hide yes)
			(effects
				(font
					(size 1.016 1.016)
					(thickness 0.1524)
				)
				(justify mirror)
			)
		)
		(property "Device Type" "C603H38"
			(at 0 -4.3434 90)
			(unlocked yes)
			(layer "B.Fab")
			(hide yes)
			(effects
				(font
					(size 1.016 1.016)
					(thickness 0.1524)
				)
				(justify mirror)
			)
		)
		(duplicate_pad_numbers_are_jumpers no)
		(fp_line
			(start 0.4064 0)
			(end -0.4064 0)
			(stroke
				(width 0.2286)
				(type default)
			)
			(layer "B.SilkS")
		)
		(fp_rect
			(start 0.635 1.1811)
			(end -0.635 -1.1811)
			(stroke
				(width 0)
				(type default)
			)
			(fill no)
			(layer "B.CrtYd")
		)
		(fp_rect
			(start 0.635 1.1811)
			(end -0.635 -1.1811)
			(stroke
				(width 0)
				(type default)
			)
			(fill no)
			(layer "B.Fab")
		)
		(pad "1" smd custom
			(at 0 -0.6604 270)
			(size 0.19685 0.19685)
			(layers "B.Cu" "B.Mask" "B.Paste")
			(net "PV_VTT_DDR_B")
			(options
				(clearance outline)
				(anchor circle)
			)
			(primitives
				(gr_poly
					(pts
						(arc
							(start 0.508 0.2921)
							(mid 0.478242 0.363942)
							(end 0.4064 0.3937)
						)
						(arc
							(start -0.4064 0.3937)
							(mid -0.478242 0.363942)
							(end -0.508 0.2921)
						)
						(arc
							(start -0.508 -0.2921)
							(mid -0.478242 -0.363942)
							(end -0.4064 -0.3937)
						)
						(arc
							(start 0.4064 -0.3937)
							(mid 0.478242 -0.363942)
							(end 0.508 -0.2921)
						)
					)
					(width 0)
					(fill yes)
				)
			)
		)
		(pad "2" smd custom
			(at 0 0.6604 270)
			(size 0.19685 0.19685)
			(layers "B.Cu" "B.Mask" "B.Paste")
			(net "GND")
			(options
				(clearance outline)
				(anchor circle)
			)
			(primitives
				(gr_poly
					(pts
						(arc
							(start 0.508 0.2921)
							(mid 0.478242 0.363942)
							(end 0.4064 0.3937)
						)
						(arc
							(start -0.4064 0.3937)
							(mid -0.478242 0.363942)
							(end -0.508 0.2921)
						)
						(arc
							(start -0.508 -0.2921)
							(mid -0.478242 -0.363942)
							(end -0.4064 -0.3937)
						)
						(arc
							(start 0.4064 -0.3937)
							(mid 0.478242 -0.363942)
							(end 0.508 -0.2921)
						)
					)
					(width 0)
					(fill yes)
				)
			)
		)
	)
)
